FILE_TYPE = MACRO_DRAWING;
SET COLOR_WIRE YELLOW;
SET COLOR_PROP ORANGE;
SET COLOR_DOT WHITE;
SET COLOR_ARC YELLOW;
SET COLOR_BODY GREEN;
SET COLOR_NOTE PURPLE;
SET PROP_DISPLAY VALUE;
SET PAGE_NUMBER P123;
FORCEADD OFFPAGE..1
(-4450 -2125);
FORCEPROP 2 LAST $XR0 45 
J 0
(-4671 -2125);
DISPLAY 0.638298 (-4671 -2125);
PAINT MONO (-4671 -2125);
FORCEPROP 2 LAST CDS_LIB standard
J 0
(-4450 -2125);
PAINT MONO (-4450 -2125);
DISPLAY INVISIBLE (-4450 -2125);
FORCEPROP 1 LAST OFFPAGE TRUE
J 0
(-4125 -2250);
DISPLAY 0.872340 (-4125 -2250);
PAINT GREEN (-4125 -2250);
DISPLAY INVISIBLE (-4125 -2250);
FORCEPROP 1 LAST COMMENT_BODY TRUE
J 0
(-4325 -2225);
DISPLAY 0.872340 (-4325 -2225);
PAINT GREEN (-4325 -2225);
DISPLAY INVISIBLE (-4325 -2225);
FORCEPROP 2 LAST PATH I1
J 0
(-4650 -2075);
DISPLAY 1.021277 (-4650 -2075);
DISPLAY INVISIBLE (-4650 -2075);
FORCEADD Q_RES..1
(-3025 -775);
FORCEPROP 1 LAST PART_NUMBER CS21502FB07
J 0
(-3075 -675);
DISPLAY 0.787234 (-3075 -675);
DISPLAY INVISIBLE (-3075 -675);
FORCEPROP 1 LAST MATERIAL CHIP
J 0
(-3025 -925);
DISPLAY 0.638298 (-3025 -925);
FORCEPROP 1 LAST PACK_TYPE 0402LF
J 0
(-2925 -875);
DISPLAY 0.638298 (-2925 -875);
FORCEPROP 1 LAST VALUE 1.5K
J 2
(-3050 -875);
DISPLAY 0.638298 (-3050 -875);
FORCEPROP 1 LAST TOLERANCE 1%
J 0
(-3025 -875);
DISPLAY 0.638298 (-3025 -875);
FORCEPROP 1 LAST WATTAGE 1/16W
J 2
(-3050 -925);
DISPLAY 0.638298 (-3050 -925);
FORCEPROP 1 LAST LOCATION R205
J 0
(-3225 -775);
DISPLAY 0.638298 (-3225 -775);
FORCEPROP 1 LASTPIN (-3125 -775) $PN 1
J 0
(-3113 -763);
DISPLAY 0.787234 (-3113 -763);
PAINT MONO (-3113 -763);
FORCEPROP 1 LASTPIN (-2925 -775) $PN 2
J 0
(-2963 -763);
DISPLAY 0.787234 (-2963 -763);
PAINT MONO (-2963 -763);
FORCEPROP 2 LAST CDS_LIB pure_quanta
J 0
(-3025 -775);
DISPLAY INVISIBLE (-3025 -775);
FORCEPROP 1 LAST PATH I10
J 0
(-3075 -625);
DISPLAY 0.978723 (-3075 -625);
PAINT WHITE (-3075 -625);
DISPLAY INVISIBLE (-3075 -625);
FORCEPROP 0 LAST $SEC 1
J 0
(-3075 -625);
DISPLAY 0.680851 (-3075 -625);
PAINT MONO (-3075 -625);
DISPLAY INVISIBLE (-3075 -625);
FORCEPROP 0 LAST CDS_SEC 1
J 0
(-3075 -625);
DISPLAY 1.021277 (-3075 -625);
DISPLAY INVISIBLE (-3075 -625);
FORCEADD BC847BPN..2
(-2025 -2125);
FORCEPROP 1 LAST PART_NUMBER BA008470026
J 0
(-1970 -2281);
DISPLAY 0.723404 (-1970 -2281);
PAINT GREEN (-1970 -2281);
DISPLAY INVISIBLE (-1970 -2281);
FORCEPROP 1 LAST MATERIAL IC
J 0
(-1970 -2368);
DISPLAY 0.723404 (-1970 -2368);
PAINT GREEN (-1970 -2368);
FORCEPROP 2 LAST PART_TYPE SMLF
J 0
(-1950 -2075);
DISPLAY 1.021277 (-1950 -2075);
FORCEPROP 2 LAST VALUE BC847BPN
J 0
(-1950 -2125);
DISPLAY 1.021277 (-1950 -2125);
FORCEPROP 1 LAST LOCATION Q140
J 0
(-1970 -2174);
DISPLAY 0.723404 (-1970 -2174);
PAINT GREEN (-1970 -2174);
FORCEPROP 0 LASTPIN (-2125 -2125) $PN 5
J 2
(-2135 -2115);
DISPLAY 0.680851 (-2135 -2115);
PAINT MONO (-2135 -2115);
FORCEPROP 0 LASTPIN (-1975 -2225) $PN 3
R 1
J 2
(-1985 -2235);
DISPLAY 0.680851 (-1985 -2235);
PAINT MONO (-1985 -2235);
FORCEPROP 0 LASTPIN (-1975 -2025) $PN 4
R 1
J 0
(-1985 -2015);
DISPLAY 0.680851 (-1985 -2015);
PAINT MONO (-1985 -2015);
FORCEPROP 2 LAST CDS_LIB pure_quanta
J 0
(-2025 -2125);
DISPLAY INVISIBLE (-2025 -2125);
FORCEPROP 1 LAST NEEDS_NO_SIZE TRUE
J 0
(-2025 -2125);
DISPLAY 0.723404 (-2025 -2125);
PAINT GREEN (-2025 -2125);
DISPLAY INVISIBLE (-2025 -2125);
FORCEPROP 1 LAST CDS_LMAN_SYM_OUTLINE -50,50,50,-50
J 0
(-2025 -2125);
DISPLAY 0.468085 (-2025 -2125);
PAINT GREEN (-2025 -2125);
DISPLAY INVISIBLE (-2025 -2125);
FORCEPROP 1 LAST PATH I11
J 0
(-2025 -2125);
DISPLAY 0.723404 (-2025 -2125);
PAINT GREEN (-2025 -2125);
DISPLAY INVISIBLE (-2025 -2125);
FORCEPROP 0 LAST $SEC 2
J 0
(-1950 -2025);
DISPLAY 0.680851 (-1950 -2025);
PAINT MONO (-1950 -2025);
DISPLAY INVISIBLE (-1950 -2025);
FORCEPROP 0 LAST CDS_SEC 2
J 0
(-1950 -2025);
DISPLAY 1.021277 (-1950 -2025);
DISPLAY INVISIBLE (-1950 -2025);
FORCEADD BC847BPN..2
(-2025 -775);
FORCEPROP 1 LAST PART_NUMBER BA008470026
J 0
(-1970 -931);
DISPLAY 0.723404 (-1970 -931);
PAINT GREEN (-1970 -931);
DISPLAY INVISIBLE (-1970 -931);
FORCEPROP 2 LAST PART_TYPE SMLF
J 0
(-1950 -725);
DISPLAY 1.021277 (-1950 -725);
FORCEPROP 1 LAST MATERIAL IC
J 0
(-1970 -1018);
DISPLAY 0.723404 (-1970 -1018);
PAINT GREEN (-1970 -1018);
FORCEPROP 2 LAST VALUE BC847BPN
J 0
(-1950 -775);
DISPLAY 1.021277 (-1950 -775);
FORCEPROP 1 LAST LOCATION Q141
J 0
(-1970 -824);
DISPLAY 0.723404 (-1970 -824);
PAINT GREEN (-1970 -824);
FORCEPROP 0 LASTPIN (-2125 -775) $PN 5
J 2
(-2135 -765);
DISPLAY 0.680851 (-2135 -765);
PAINT MONO (-2135 -765);
FORCEPROP 0 LASTPIN (-1975 -875) $PN 3
R 1
J 2
(-1985 -885);
DISPLAY 0.680851 (-1985 -885);
PAINT MONO (-1985 -885);
FORCEPROP 0 LASTPIN (-1975 -675) $PN 4
R 1
J 0
(-1985 -665);
DISPLAY 0.680851 (-1985 -665);
PAINT MONO (-1985 -665);
FORCEPROP 2 LAST CDS_LIB pure_quanta
J 0
(-2025 -775);
DISPLAY INVISIBLE (-2025 -775);
FORCEPROP 1 LAST NEEDS_NO_SIZE TRUE
J 0
(-2025 -775);
DISPLAY 0.723404 (-2025 -775);
PAINT GREEN (-2025 -775);
DISPLAY INVISIBLE (-2025 -775);
FORCEPROP 1 LAST CDS_LMAN_SYM_OUTLINE -50,50,50,-50
J 0
(-2025 -775);
DISPLAY 0.468085 (-2025 -775);
PAINT GREEN (-2025 -775);
DISPLAY INVISIBLE (-2025 -775);
FORCEPROP 1 LAST PATH I12
J 0
(-2025 -775);
DISPLAY 0.723404 (-2025 -775);
PAINT GREEN (-2025 -775);
DISPLAY INVISIBLE (-2025 -775);
FORCEPROP 0 LAST $SEC 2
J 0
(-1950 -675);
DISPLAY 0.680851 (-1950 -675);
PAINT MONO (-1950 -675);
DISPLAY INVISIBLE (-1950 -675);
FORCEPROP 0 LAST CDS_SEC 2
J 0
(-1950 -675);
DISPLAY 1.021277 (-1950 -675);
DISPLAY INVISIBLE (-1950 -675);
FORCEADD UNIVERSAL_POWER..1
(-1975 -1875);
FORCEPROP 3 LASTPIN (-1975 -1925) SIG_NAME PVNN_TERM_CPU1\g
J 0
(-1965 -1915);
DISPLAY 0.659574 (-1965 -1915);
PAINT MONO (-1965 -1915);
DISPLAY INVISIBLE (-1965 -1915);
FORCEPROP 1 LAST HDL_POWER PVNN_TERM_CPU1
J 1
(-1975 -1825);
DISPLAY 0.872340 (-1975 -1825);
PAINT GREEN (-1975 -1825);
FORCEPROP 2 LAST CDS_LIB logical_power
J 0
(-1975 -1875);
DISPLAY INVISIBLE (-1975 -1875);
FORCEPROP 1 LAST PATH I13
J 0
(-1925 -1850);
DISPLAY 0.872340 (-1925 -1850);
PAINT AQUA (-1925 -1850);
DISPLAY INVISIBLE (-1925 -1850);
FORCEADD Q_RES..1
(-1250 -2375);
FORCEPROP 1 LAST PART_NUMBER CS21502FB07
J 0
(-1300 -2275);
DISPLAY 0.787234 (-1300 -2275);
DISPLAY INVISIBLE (-1300 -2275);
FORCEPROP 1 LAST MATERIAL CHIP
J 0
(-1250 -2525);
DISPLAY 0.638298 (-1250 -2525);
FORCEPROP 1 LAST PACK_TYPE 0402LF
J 0
(-1150 -2475);
DISPLAY 0.638298 (-1150 -2475);
FORCEPROP 1 LAST VALUE 1.5K
J 2
(-1275 -2475);
DISPLAY 0.638298 (-1275 -2475);
FORCEPROP 1 LAST $LOCATION R4410
J 0
(-1450 -2375);
DISPLAY 0.638298 (-1450 -2375);
FORCEPROP 1 LASTPIN (-1350 -2375) $PN 1
J 0
(-1338 -2363);
DISPLAY 0.787234 (-1338 -2363);
PAINT MONO (-1338 -2363);
FORCEPROP 1 LASTPIN (-1150 -2375) $PN 2
J 0
(-1188 -2363);
DISPLAY 0.787234 (-1188 -2363);
PAINT MONO (-1188 -2363);
FORCEPROP 2 LAST CDS_LIB pure_quanta
J 0
(-1250 -2375);
DISPLAY INVISIBLE (-1250 -2375);
FORCEPROP 1 LAST TOLERANCE 1%
J 0
(-1250 -2475);
DISPLAY 0.638298 (-1250 -2475);
DISPLAY INVISIBLE (-1250 -2475);
FORCEPROP 1 LAST WATTAGE 1/16W
J 2
(-1275 -2525);
DISPLAY 0.638298 (-1275 -2525);
DISPLAY INVISIBLE (-1275 -2525);
FORCEPROP 1 LAST PATH I14
J 0
(-1300 -2225);
DISPLAY 0.978723 (-1300 -2225);
PAINT WHITE (-1300 -2225);
DISPLAY INVISIBLE (-1300 -2225);
FORCEPROP 0 LAST CDS_LOCATION R4410
J 0
(-1425 -2325);
DISPLAY 1.021277 (-1425 -2325);
DISPLAY INVISIBLE (-1425 -2325);
FORCEPROP 0 LAST $SEC 1
J 0
(-1425 -2325);
DISPLAY 0.680851 (-1425 -2325);
PAINT MONO (-1425 -2325);
DISPLAY INVISIBLE (-1425 -2325);
FORCEPROP 0 LAST CDS_SEC 1
J 0
(-1425 -2325);
DISPLAY 1.021277 (-1425 -2325);
DISPLAY INVISIBLE (-1425 -2325);
FORCEADD Q_RES..1
(-1250 -1025);
FORCEPROP 1 LAST PART_NUMBER CS21502FB07
J 0
(-1300 -925);
DISPLAY 0.787234 (-1300 -925);
DISPLAY INVISIBLE (-1300 -925);
FORCEPROP 1 LAST PACK_TYPE 0402LF
J 0
(-1150 -1125);
DISPLAY 0.638298 (-1150 -1125);
FORCEPROP 1 LAST VALUE 1.5K
J 2
(-1275 -1125);
DISPLAY 0.638298 (-1275 -1125);
FORCEPROP 1 LAST MATERIAL CHIP
J 0
(-1250 -1175);
DISPLAY 0.638298 (-1250 -1175);
FORCEPROP 1 LAST $LOCATION R4409
J 0
(-1450 -1025);
DISPLAY 0.638298 (-1450 -1025);
FORCEPROP 1 LASTPIN (-1350 -1025) $PN 1
J 0
(-1338 -1013);
DISPLAY 0.787234 (-1338 -1013);
PAINT MONO (-1338 -1013);
FORCEPROP 1 LASTPIN (-1150 -1025) $PN 2
J 0
(-1188 -1013);
DISPLAY 0.787234 (-1188 -1013);
PAINT MONO (-1188 -1013);
FORCEPROP 2 LAST CDS_LIB pure_quanta
J 0
(-1250 -1025);
DISPLAY INVISIBLE (-1250 -1025);
FORCEPROP 1 LAST TOLERANCE 1%
J 0
(-1250 -1125);
DISPLAY 0.638298 (-1250 -1125);
DISPLAY INVISIBLE (-1250 -1125);
FORCEPROP 1 LAST WATTAGE 1/16W
J 2
(-1275 -1175);
DISPLAY 0.638298 (-1275 -1175);
DISPLAY INVISIBLE (-1275 -1175);
FORCEPROP 1 LAST PATH I15
J 0
(-1300 -875);
DISPLAY 0.978723 (-1300 -875);
PAINT WHITE (-1300 -875);
DISPLAY INVISIBLE (-1300 -875);
FORCEPROP 0 LAST CDS_LOCATION R4409
J 0
(-1425 -975);
DISPLAY 1.021277 (-1425 -975);
DISPLAY INVISIBLE (-1425 -975);
FORCEPROP 0 LAST $SEC 1
J 0
(-1425 -975);
DISPLAY 0.680851 (-1425 -975);
PAINT MONO (-1425 -975);
DISPLAY INVISIBLE (-1425 -975);
FORCEPROP 0 LAST CDS_SEC 1
J 0
(-1425 -975);
DISPLAY 1.021277 (-1425 -975);
DISPLAY INVISIBLE (-1425 -975);
FORCEADD BC847BPN..1
(-475 -2375);
FORCEPROP 1 LAST PART_NUMBER BA008470026
J 0
(-420 -2531);
DISPLAY 0.723404 (-420 -2531);
PAINT GREEN (-420 -2531);
DISPLAY INVISIBLE (-420 -2531);
FORCEPROP 2 LAST PART_TYPE SMLF
J 0
(-400 -2325);
DISPLAY 1.021277 (-400 -2325);
FORCEPROP 1 LAST MATERIAL IC
J 0
(-420 -2618);
DISPLAY 0.723404 (-420 -2618);
PAINT GREEN (-420 -2618);
FORCEPROP 2 LAST VALUE BC847BPN
J 0
(-400 -2375);
DISPLAY 1.021277 (-400 -2375);
FORCEPROP 1 LAST LOCATION Q140
J 0
(-420 -2424);
DISPLAY 0.723404 (-420 -2424);
PAINT GREEN (-420 -2424);
FORCEPROP 0 LASTPIN (-575 -2375) $PN 2
J 2
(-585 -2365);
DISPLAY 0.680851 (-585 -2365);
PAINT MONO (-585 -2365);
FORCEPROP 0 LASTPIN (-425 -2475) $PN 6
R 1
J 2
(-435 -2485);
DISPLAY 0.680851 (-435 -2485);
PAINT MONO (-435 -2485);
FORCEPROP 0 LASTPIN (-425 -2275) $PN 1
R 1
J 0
(-435 -2265);
DISPLAY 0.680851 (-435 -2265);
PAINT MONO (-435 -2265);
FORCEPROP 2 LAST CDS_LIB pure_quanta
J 0
(-475 -2375);
DISPLAY INVISIBLE (-475 -2375);
FORCEPROP 1 LAST NEEDS_NO_SIZE TRUE
J 0
(-475 -2375);
DISPLAY 0.723404 (-475 -2375);
PAINT GREEN (-475 -2375);
DISPLAY INVISIBLE (-475 -2375);
FORCEPROP 1 LAST CDS_LMAN_SYM_OUTLINE -50,50,50,-50
J 0
(-475 -2375);
DISPLAY 0.468085 (-475 -2375);
PAINT GREEN (-475 -2375);
DISPLAY INVISIBLE (-475 -2375);
FORCEPROP 1 LAST PATH I16
J 0
(-475 -2375);
DISPLAY 0.723404 (-475 -2375);
PAINT GREEN (-475 -2375);
DISPLAY INVISIBLE (-475 -2375);
FORCEPROP 0 LAST $SEC 1
J 0
(-400 -2275);
DISPLAY 0.680851 (-400 -2275);
PAINT MONO (-400 -2275);
DISPLAY INVISIBLE (-400 -2275);
FORCEPROP 0 LAST CDS_SEC 1
J 0
(-400 -2275);
DISPLAY 1.021277 (-400 -2275);
DISPLAY INVISIBLE (-400 -2275);
FORCEADD UNIVERSAL_GND..1
(-375 -2050);
FORCEPROP 3 LASTPIN (-375 -2000) SIG_NAME GND\g
J 0
(-365 -1990);
DISPLAY 0.659574 (-365 -1990);
PAINT MONO (-365 -1990);
DISPLAY INVISIBLE (-365 -1990);
FORCEPROP 2 LAST CDS_LIB logical_power
J 0
(-375 -2050);
DISPLAY INVISIBLE (-375 -2050);
FORCEPROP 1 LAST HDL_POWER GND
J 1
(-350 -2125);
DISPLAY 0.872340 (-350 -2125);
PAINT GREEN (-350 -2125);
DISPLAY INVISIBLE (-350 -2125);
FORCEPROP 1 LAST PATH I17
J 0
(-300 -2050);
DISPLAY 0.872340 (-300 -2050);
PAINT AQUA (-300 -2050);
DISPLAY INVISIBLE (-300 -2050);
FORCEADD BC847BPN..1
(-475 -1025);
FORCEPROP 1 LAST PART_NUMBER BA008470026
J 0
(-420 -1181);
DISPLAY 0.723404 (-420 -1181);
PAINT GREEN (-420 -1181);
DISPLAY INVISIBLE (-420 -1181);
FORCEPROP 2 LAST PART_TYPE SMLF
J 0
(-400 -975);
DISPLAY 1.021277 (-400 -975);
FORCEPROP 1 LAST MATERIAL IC
J 0
(-420 -1268);
DISPLAY 0.723404 (-420 -1268);
PAINT GREEN (-420 -1268);
FORCEPROP 2 LAST VALUE BC847BPN
J 0
(-400 -1025);
DISPLAY 1.021277 (-400 -1025);
FORCEPROP 1 LAST LOCATION Q141
J 0
(-420 -1074);
DISPLAY 0.723404 (-420 -1074);
PAINT GREEN (-420 -1074);
FORCEPROP 0 LASTPIN (-575 -1025) $PN 2
J 2
(-585 -1015);
DISPLAY 0.680851 (-585 -1015);
PAINT MONO (-585 -1015);
FORCEPROP 0 LASTPIN (-425 -1125) $PN 6
R 1
J 2
(-435 -1135);
DISPLAY 0.680851 (-435 -1135);
PAINT MONO (-435 -1135);
FORCEPROP 0 LASTPIN (-425 -925) $PN 1
R 1
J 0
(-435 -915);
DISPLAY 0.680851 (-435 -915);
PAINT MONO (-435 -915);
FORCEPROP 2 LAST CDS_LIB pure_quanta
J 0
(-475 -1025);
DISPLAY INVISIBLE (-475 -1025);
FORCEPROP 1 LAST NEEDS_NO_SIZE TRUE
J 0
(-475 -1025);
DISPLAY 0.723404 (-475 -1025);
PAINT GREEN (-475 -1025);
DISPLAY INVISIBLE (-475 -1025);
FORCEPROP 1 LAST CDS_LMAN_SYM_OUTLINE -50,50,50,-50
J 0
(-475 -1025);
DISPLAY 0.468085 (-475 -1025);
PAINT GREEN (-475 -1025);
DISPLAY INVISIBLE (-475 -1025);
FORCEPROP 1 LAST PATH I18
J 0
(-475 -1025);
DISPLAY 0.723404 (-475 -1025);
PAINT GREEN (-475 -1025);
DISPLAY INVISIBLE (-475 -1025);
FORCEPROP 0 LAST $SEC 1
J 0
(-400 -925);
DISPLAY 0.680851 (-400 -925);
PAINT MONO (-400 -925);
DISPLAY INVISIBLE (-400 -925);
FORCEPROP 0 LAST CDS_SEC 1
J 0
(-400 -925);
DISPLAY 1.021277 (-400 -925);
DISPLAY INVISIBLE (-400 -925);
FORCEADD Q_RES..2
(-3375 -500);
FORCEPROP 1 LAST PART_NUMBER CS11002FB07
J 0
(-3350 -675);
DISPLAY 0.510638 (-3350 -675);
DISPLAY INVISIBLE (-3350 -675);
FORCEPROP 1 LAST VALUE 100
J 0
(-3345 -475);
DISPLAY 0.510638 (-3345 -475);
FORCEPROP 1 LAST TOLERANCE 1%
J 0
(-3345 -525);
DISPLAY 0.510638 (-3345 -525);
FORCEPROP 1 LAST MATERIAL CHIP
J 0
(-3350 -625);
DISPLAY 0.510638 (-3350 -625);
FORCEPROP 1 LAST WATTAGE 1/16W
J 0
(-3350 -575);
DISPLAY 0.510638 (-3350 -575);
FORCEPROP 1 LAST PACK_TYPE 0402LF
J 0
(-3350 -725);
DISPLAY 0.510638 (-3350 -725);
FORCEPROP 1 LAST LOCATION R200
J 0
(-3345 -425);
DISPLAY 0.638298 (-3345 -425);
FORCEPROP 1 LASTPIN (-3375 -400) $PN 1
J 0
(-3370 -438);
DISPLAY 0.787234 (-3370 -438);
PAINT MONO (-3370 -438);
FORCEPROP 1 LASTPIN (-3375 -600) $PN 2
J 0
(-3370 -590);
DISPLAY 0.787234 (-3370 -590);
PAINT MONO (-3370 -590);
FORCEPROP 2 LAST CDS_LIB pure_quanta
J 0
(-3375 -500);
DISPLAY INVISIBLE (-3375 -500);
FORCEPROP 1 LAST PATH I19
J 0
(-3325 -325);
DISPLAY 0.978723 (-3325 -325);
PAINT WHITE (-3325 -325);
DISPLAY INVISIBLE (-3325 -325);
FORCEPROP 0 LAST $SEC 1
J 0
(-3325 -375);
DISPLAY 0.680851 (-3325 -375);
PAINT MONO (-3325 -375);
DISPLAY INVISIBLE (-3325 -375);
FORCEPROP 0 LAST CDS_SEC 1
J 0
(-3325 -375);
DISPLAY 1.021277 (-3325 -375);
DISPLAY INVISIBLE (-3325 -375);
FORCEADD OFFPAGE..1
(-4450 -775);
FORCEPROP 2 LAST $XR0 14 
J 0
(-4671 -775);
DISPLAY 0.638298 (-4671 -775);
PAINT MONO (-4671 -775);
FORCEPROP 2 LAST CDS_LIB standard
J 0
(-4450 -775);
PAINT MONO (-4450 -775);
DISPLAY INVISIBLE (-4450 -775);
FORCEPROP 1 LAST OFFPAGE TRUE
J 0
(-4125 -900);
DISPLAY 0.872340 (-4125 -900);
PAINT GREEN (-4125 -900);
DISPLAY INVISIBLE (-4125 -900);
FORCEPROP 1 LAST COMMENT_BODY TRUE
J 0
(-4325 -875);
DISPLAY 0.872340 (-4325 -875);
PAINT GREEN (-4325 -875);
DISPLAY INVISIBLE (-4325 -875);
FORCEPROP 2 LAST PATH I2
J 0
(-4650 -725);
DISPLAY 1.021277 (-4650 -725);
DISPLAY INVISIBLE (-4650 -725);
FORCEADD UNIVERSAL_POWER..1
(-3375 -300);
FORCEPROP 3 LASTPIN (-3375 -350) SIG_NAME PVNN_TERM_CPU0\g
J 0
(-3365 -340);
DISPLAY 0.659574 (-3365 -340);
PAINT MONO (-3365 -340);
DISPLAY INVISIBLE (-3365 -340);
FORCEPROP 1 LAST HDL_POWER PVNN_TERM_CPU0
J 1
(-3375 -250);
DISPLAY 0.872340 (-3375 -250);
PAINT GREEN (-3375 -250);
FORCEPROP 2 LAST CDS_LIB logical_power
J 0
(-3375 -300);
DISPLAY INVISIBLE (-3375 -300);
FORCEPROP 1 LAST PATH I20
J 0
(-3325 -275);
DISPLAY 0.872340 (-3325 -275);
PAINT AQUA (-3325 -275);
DISPLAY INVISIBLE (-3325 -275);
FORCEADD UNIVERSAL_POWER..1
(-1975 -525);
FORCEPROP 3 LASTPIN (-1975 -575) SIG_NAME PVNN_TERM_CPU0\g
J 0
(-1965 -565);
DISPLAY 0.659574 (-1965 -565);
PAINT MONO (-1965 -565);
DISPLAY INVISIBLE (-1965 -565);
FORCEPROP 1 LAST HDL_POWER PVNN_TERM_CPU0
J 1
(-1975 -475);
DISPLAY 0.872340 (-1975 -475);
PAINT GREEN (-1975 -475);
FORCEPROP 2 LAST CDS_LIB logical_power
J 0
(-1975 -525);
DISPLAY INVISIBLE (-1975 -525);
FORCEPROP 1 LAST PATH I21
J 0
(-1925 -500);
DISPLAY 0.872340 (-1925 -500);
PAINT AQUA (-1925 -500);
DISPLAY INVISIBLE (-1925 -500);
FORCEADD UNIVERSAL_GND..1
(-375 -700);
FORCEPROP 3 LASTPIN (-375 -650) SIG_NAME GND\g
J 0
(-365 -640);
DISPLAY 0.659574 (-365 -640);
PAINT MONO (-365 -640);
DISPLAY INVISIBLE (-365 -640);
FORCEPROP 2 LAST CDS_LIB logical_power
J 0
(-375 -700);
DISPLAY INVISIBLE (-375 -700);
FORCEPROP 1 LAST HDL_POWER GND
J 1
(-350 -775);
DISPLAY 0.872340 (-350 -775);
PAINT GREEN (-350 -775);
DISPLAY INVISIBLE (-350 -775);
FORCEPROP 1 LAST PATH I22
J 0
(-300 -700);
DISPLAY 0.872340 (-300 -700);
PAINT AQUA (-300 -700);
DISPLAY INVISIBLE (-300 -700);
FORCEADD Q_RES..2
(1025 -5350);
FORCEPROP 1 LAST PART_NUMBER CS13012FB02
J 0
(1065 -5475);
DISPLAY 0.510638 (1065 -5475);
DISPLAY INVISIBLE (1065 -5475);
FORCEPROP 1 LAST WATTAGE 1/16W
J 0
(1065 -5375);
DISPLAY 0.510638 (1065 -5375);
FORCEPROP 1 LAST MATERIAL CHIP
J 0
(1065 -5425);
DISPLAY 0.510638 (1065 -5425);
FORCEPROP 1 LAST PACK_TYPE 0402LF
J 0
(1065 -5525);
DISPLAY 0.510638 (1065 -5525);
FORCEPROP 1 LAST VALUE 301
J 0
(1070 -5275);
DISPLAY 0.510638 (1070 -5275);
FORCEPROP 1 LAST TOLERANCE 1%
J 0
(1070 -5325);
DISPLAY 0.510638 (1070 -5325);
FORCEPROP 1 LAST LOCATION R198
J 0
(1070 -5225);
DISPLAY 0.978723 (1070 -5225);
FORCEPROP 1 LASTPIN (1025 -5250) $PN 1
J 0
(1030 -5288);
DISPLAY 0.787234 (1030 -5288);
PAINT MONO (1030 -5288);
FORCEPROP 1 LASTPIN (1025 -5450) $PN 2
J 0
(1030 -5440);
DISPLAY 0.787234 (1030 -5440);
PAINT MONO (1030 -5440);
FORCEPROP 2 LAST CDS_LIB pure_quanta
J 0
(1025 -5350);
DISPLAY INVISIBLE (1025 -5350);
FORCEPROP 1 LAST PATH I23
J 0
(1075 -5175);
DISPLAY 0.978723 (1075 -5175);
PAINT WHITE (1075 -5175);
DISPLAY INVISIBLE (1075 -5175);
FORCEPROP 0 LAST $SEC 1
J 0
(1075 -5175);
DISPLAY 0.680851 (1075 -5175);
PAINT MONO (1075 -5175);
DISPLAY INVISIBLE (1075 -5175);
FORCEPROP 0 LAST CDS_SEC 1
J 0
(1075 -5175);
DISPLAY 1.021277 (1075 -5175);
DISPLAY INVISIBLE (1075 -5175);
FORCEADD UNIVERSAL_POWER..1
(1025 -5100);
FORCEPROP 3 LASTPIN (1025 -5150) SIG_NAME PVNN_TERM_CPU1\g
J 0
(1035 -5140);
DISPLAY 0.659574 (1035 -5140);
PAINT MONO (1035 -5140);
DISPLAY INVISIBLE (1035 -5140);
FORCEPROP 1 LAST HDL_POWER PVNN_TERM_CPU1
J 1
(1025 -5050);
DISPLAY 0.872340 (1025 -5050);
PAINT GREEN (1025 -5050);
FORCEPROP 2 LAST CDS_LIB logical_power
J 0
(1025 -5100);
PAINT MONO (1025 -5100);
DISPLAY INVISIBLE (1025 -5100);
FORCEPROP 1 LAST PATH I24
J 0
(1075 -5075);
DISPLAY 0.872340 (1075 -5075);
PAINT AQUA (1075 -5075);
DISPLAY INVISIBLE (1075 -5075);
FORCEADD OFFPAGE..2
(1200 -5600);
FORCEPROP 2 LAST $XR0 45 
J 0
(1389 -5600);
DISPLAY 0.638298 (1389 -5600);
PAINT MONO (1389 -5600);
FORCEPROP 2 LAST CDS_LIB standard
J 0
(1200 -5600);
DISPLAY INVISIBLE (1200 -5600);
FORCEPROP 1 LAST OFFPAGE TRUE
J 0
(1525 -5725);
DISPLAY 0.872340 (1525 -5725);
PAINT GREEN (1525 -5725);
DISPLAY INVISIBLE (1525 -5725);
FORCEPROP 1 LAST COMMENT_BODY TRUE
J 0
(1155 -5695);
DISPLAY 0.872340 (1155 -5695);
PAINT GREEN (1155 -5695);
DISPLAY INVISIBLE (1155 -5695);
FORCEPROP 2 LAST PATH I25
J 0
(1400 -5550);
DISPLAY 1.021277 (1400 -5550);
DISPLAY INVISIBLE (1400 -5550);
FORCEADD OFFPAGE..2
(1200 -4925);
FORCEPROP 2 LAST $XR0 14 
J 0
(1389 -4925);
DISPLAY 0.638298 (1389 -4925);
PAINT MONO (1389 -4925);
FORCEPROP 2 LAST CDS_LIB standard
J 0
(1200 -4925);
DISPLAY INVISIBLE (1200 -4925);
FORCEPROP 1 LAST OFFPAGE TRUE
J 0
(1525 -5050);
DISPLAY 0.872340 (1525 -5050);
PAINT GREEN (1525 -5050);
DISPLAY INVISIBLE (1525 -5050);
FORCEPROP 1 LAST COMMENT_BODY TRUE
J 0
(1155 -5020);
DISPLAY 0.872340 (1155 -5020);
PAINT GREEN (1155 -5020);
DISPLAY INVISIBLE (1155 -5020);
FORCEPROP 2 LAST PATH I26
J 0
(1400 -4875);
DISPLAY 1.021277 (1400 -4875);
DISPLAY INVISIBLE (1400 -4875);
FORCEADD Q_RES..2
(1025 -4675);
FORCEPROP 1 LAST PART_NUMBER CS13012FB02
J 0
(1065 -4800);
DISPLAY 0.510638 (1065 -4800);
DISPLAY INVISIBLE (1065 -4800);
FORCEPROP 1 LAST PACK_TYPE 0402LF
J 0
(1065 -4850);
DISPLAY 0.510638 (1065 -4850);
FORCEPROP 1 LAST VALUE 301
J 0
(1070 -4600);
DISPLAY 0.510638 (1070 -4600);
FORCEPROP 1 LAST WATTAGE 1/16W
J 0
(1065 -4700);
DISPLAY 0.510638 (1065 -4700);
FORCEPROP 1 LAST MATERIAL CHIP
J 0
(1065 -4750);
DISPLAY 0.510638 (1065 -4750);
FORCEPROP 1 LAST TOLERANCE 1%
J 0
(1070 -4650);
DISPLAY 0.510638 (1070 -4650);
FORCEPROP 1 LAST LOCATION R197
J 0
(1070 -4550);
DISPLAY 0.978723 (1070 -4550);
FORCEPROP 1 LASTPIN (1025 -4575) $PN 1
J 0
(1030 -4613);
DISPLAY 0.787234 (1030 -4613);
PAINT MONO (1030 -4613);
FORCEPROP 1 LASTPIN (1025 -4775) $PN 2
J 0
(1030 -4765);
DISPLAY 0.787234 (1030 -4765);
PAINT MONO (1030 -4765);
FORCEPROP 2 LAST CDS_LIB pure_quanta
J 0
(1025 -4675);
DISPLAY INVISIBLE (1025 -4675);
FORCEPROP 1 LAST PATH I27
J 0
(1075 -4500);
DISPLAY 0.978723 (1075 -4500);
PAINT WHITE (1075 -4500);
DISPLAY INVISIBLE (1075 -4500);
FORCEPROP 0 LAST $SEC 1
J 0
(1075 -4500);
DISPLAY 0.680851 (1075 -4500);
PAINT MONO (1075 -4500);
DISPLAY INVISIBLE (1075 -4500);
FORCEPROP 0 LAST CDS_SEC 1
J 0
(1075 -4500);
DISPLAY 1.021277 (1075 -4500);
DISPLAY INVISIBLE (1075 -4500);
FORCEADD UNIVERSAL_POWER..1
(1025 -4375);
FORCEPROP 3 LASTPIN (1025 -4425) SIG_NAME PVNN_TERM_CPU0\g
J 0
(1035 -4415);
DISPLAY 0.659574 (1035 -4415);
PAINT MONO (1035 -4415);
DISPLAY INVISIBLE (1035 -4415);
FORCEPROP 1 LAST HDL_POWER PVNN_TERM_CPU0
J 1
(1025 -4325);
DISPLAY 0.872340 (1025 -4325);
PAINT GREEN (1025 -4325);
FORCEPROP 2 LAST CDS_LIB logical_power
J 0
(1025 -4375);
PAINT MONO (1025 -4375);
DISPLAY INVISIBLE (1025 -4375);
FORCEPROP 1 LAST PATH I28
J 0
(1075 -4350);
DISPLAY 0.872340 (1075 -4350);
PAINT AQUA (1075 -4350);
DISPLAY INVISIBLE (1075 -4350);
FORCEADD Q_RES..2
(375 -2225);
FORCEPROP 1 LAST PART_NUMBER CS24752FB03
J 0
(400 -2350);
DISPLAY 0.978723 (400 -2350);
DISPLAY INVISIBLE (400 -2350);
FORCEPROP 1 LAST WATTAGE 1/16W
J 0
(415 -2250);
DISPLAY 0.978723 (415 -2250);
FORCEPROP 1 LAST TOLERANCE 1%
J 0
(420 -2200);
DISPLAY 0.978723 (420 -2200);
FORCEPROP 1 LAST VALUE 4.75K
J 0
(420 -2150);
DISPLAY 0.978723 (420 -2150);
FORCEPROP 1 LAST MATERIAL CHIP
J 0
(415 -2300);
DISPLAY 0.978723 (415 -2300);
FORCEPROP 1 LAST PACK_TYPE 0402LF
J 0
(415 -2400);
DISPLAY 0.978723 (415 -2400);
FORCEPROP 1 LAST $LOCATION R4412
J 0
(420 -2100);
DISPLAY 0.978723 (420 -2100);
FORCEPROP 1 LASTPIN (375 -2125) $PN 1
J 0
(380 -2163);
DISPLAY 0.787234 (380 -2163);
PAINT MONO (380 -2163);
FORCEPROP 1 LASTPIN (375 -2325) $PN 2
J 0
(380 -2315);
DISPLAY 0.787234 (380 -2315);
PAINT MONO (380 -2315);
FORCEPROP 2 LAST CDS_LIB pure_quanta
J 0
(375 -2225);
DISPLAY INVISIBLE (375 -2225);
FORCEPROP 1 LAST PATH I29
J 0
(425 -2050);
DISPLAY 0.978723 (425 -2050);
PAINT WHITE (425 -2050);
DISPLAY INVISIBLE (425 -2050);
FORCEPROP 0 LAST CDS_LOCATION R4412
J 0
(425 -2050);
DISPLAY 1.021277 (425 -2050);
DISPLAY INVISIBLE (425 -2050);
FORCEPROP 0 LAST $SEC 1
J 0
(425 -2050);
DISPLAY 0.680851 (425 -2050);
PAINT MONO (425 -2050);
DISPLAY INVISIBLE (425 -2050);
FORCEPROP 2 LAST CDS_SEC 1
J 0
(425 -2000);
DISPLAY 1.021277 (425 -2000);
DISPLAY INVISIBLE (425 -2000);
FORCEADD OFFPAGE..1
(-3575 -4925);
FORCEPROP 2 LAST $XR0 216 
J 0
(-3857 -4925);
DISPLAY 0.638298 (-3857 -4925);
PAINT MONO (-3857 -4925);
FORCEPROP 2 LAST CDS_LIB standard
J 0
(-3575 -4925);
PAINT MONO (-3575 -4925);
DISPLAY INVISIBLE (-3575 -4925);
FORCEPROP 1 LAST OFFPAGE TRUE
J 0
(-3250 -5050);
DISPLAY 0.872340 (-3250 -5050);
PAINT GREEN (-3250 -5050);
DISPLAY INVISIBLE (-3250 -5050);
FORCEPROP 1 LAST COMMENT_BODY TRUE
J 0
(-3450 -5025);
DISPLAY 0.872340 (-3450 -5025);
PAINT GREEN (-3450 -5025);
DISPLAY INVISIBLE (-3450 -5025);
FORCEPROP 2 LAST PATH I3
J 0
(-3850 -4875);
DISPLAY 1.021277 (-3850 -4875);
DISPLAY INVISIBLE (-3850 -4875);
FORCEADD UNIVERSAL_POWER..1
(375 -1975);
FORCEPROP 3 LASTPIN (375 -2025) SIG_NAME P3V3\g
J 0
(385 -2015);
DISPLAY 0.659574 (385 -2015);
PAINT MONO (385 -2015);
DISPLAY INVISIBLE (385 -2015);
FORCEPROP 1 LAST HDL_POWER P3V3
J 1
(375 -1925);
DISPLAY 0.872340 (375 -1925);
PAINT GREEN (375 -1925);
FORCEPROP 2 LAST CDS_LIB logical_power
J 0
(375 -1975);
PAINT MONO (375 -1975);
DISPLAY INVISIBLE (375 -1975);
FORCEPROP 1 LAST PATH I30
J 0
(425 -1950);
DISPLAY 0.872340 (425 -1950);
PAINT AQUA (425 -1950);
DISPLAY INVISIBLE (425 -1950);
FORCEADD Q_RES..1
(1025 -2600);
FORCEPROP 1 LAST PART_NUMBER CS03322FB03
J 0
(975 -2500);
DISPLAY 0.787234 (975 -2500);
DISPLAY INVISIBLE (975 -2500);
FORCEPROP 1 LAST MATERIAL CHIP
J 0
(1025 -2750);
DISPLAY 0.787234 (1025 -2750);
FORCEPROP 1 LAST PACK_TYPE 0402LF
J 0
(1275 -2750);
DISPLAY 0.787234 (1275 -2750);
FORCEPROP 1 LAST WATTAGE 1/16W
J 2
(1000 -2750);
DISPLAY 0.787234 (1000 -2750);
FORCEPROP 1 LAST VALUE 33.2
J 2
(1000 -2700);
DISPLAY 0.787234 (1000 -2700);
FORCEPROP 1 LAST TOLERANCE 1%
J 0
(1025 -2700);
DISPLAY 0.787234 (1025 -2700);
FORCEPROP 1 LAST $LOCATION R4414
J 0
(800 -2600);
DISPLAY 0.787234 (800 -2600);
FORCEPROP 1 LASTPIN (925 -2600) $PN 1
J 0
(937 -2588);
DISPLAY 0.787234 (937 -2588);
PAINT MONO (937 -2588);
FORCEPROP 1 LASTPIN (1125 -2600) $PN 2
J 0
(1087 -2588);
DISPLAY 0.787234 (1087 -2588);
PAINT MONO (1087 -2588);
FORCEPROP 2 LAST CDS_LIB pure_quanta
J 0
(1025 -2600);
DISPLAY INVISIBLE (1025 -2600);
FORCEPROP 1 LAST PATH I31
J 0
(975 -2450);
DISPLAY 0.978723 (975 -2450);
PAINT WHITE (975 -2450);
DISPLAY INVISIBLE (975 -2450);
FORCEPROP 0 LAST CDS_LOCATION R4414
J 0
(975 -2450);
DISPLAY 1.021277 (975 -2450);
DISPLAY INVISIBLE (975 -2450);
FORCEPROP 0 LAST $SEC 1
J 0
(975 -2450);
DISPLAY 0.680851 (975 -2450);
PAINT MONO (975 -2450);
DISPLAY INVISIBLE (975 -2450);
FORCEPROP 0 LAST CDS_SEC 1
J 0
(975 -2450);
DISPLAY 1.021277 (975 -2450);
DISPLAY INVISIBLE (975 -2450);
FORCEADD Q_RES..2
(375 -875);
FORCEPROP 1 LAST PART_NUMBER CS24752FB03
J 0
(400 -1000);
DISPLAY 0.978723 (400 -1000);
DISPLAY INVISIBLE (400 -1000);
FORCEPROP 1 LAST MATERIAL CHIP
J 0
(415 -950);
DISPLAY 0.978723 (415 -950);
FORCEPROP 1 LAST VALUE 4.75K
J 0
(420 -800);
DISPLAY 0.978723 (420 -800);
FORCEPROP 1 LAST WATTAGE 1/16W
J 0
(415 -900);
DISPLAY 0.978723 (415 -900);
FORCEPROP 1 LAST TOLERANCE 1%
J 0
(420 -850);
DISPLAY 0.978723 (420 -850);
FORCEPROP 1 LAST PACK_TYPE 0402LF
J 0
(415 -1050);
DISPLAY 0.978723 (415 -1050);
FORCEPROP 1 LAST $LOCATION R4411
J 0
(420 -750);
DISPLAY 0.787234 (420 -750);
FORCEPROP 1 LASTPIN (375 -775) $PN 1
J 0
(380 -813);
DISPLAY 0.787234 (380 -813);
PAINT MONO (380 -813);
FORCEPROP 1 LASTPIN (375 -975) $PN 2
J 0
(380 -965);
DISPLAY 0.787234 (380 -965);
PAINT MONO (380 -965);
FORCEPROP 2 LAST CDS_LIB pure_quanta
J 0
(375 -875);
DISPLAY INVISIBLE (375 -875);
FORCEPROP 1 LAST PATH I32
J 0
(425 -700);
DISPLAY 0.978723 (425 -700);
PAINT WHITE (425 -700);
DISPLAY INVISIBLE (425 -700);
FORCEPROP 2 LAST CDS_LOCATION R4411
J 0
(425 -650);
DISPLAY 1.021277 (425 -650);
DISPLAY INVISIBLE (425 -650);
FORCEPROP 0 LAST $SEC 1
J 0
(425 -700);
DISPLAY 0.680851 (425 -700);
PAINT MONO (425 -700);
DISPLAY INVISIBLE (425 -700);
FORCEPROP 2 LAST CDS_SEC 1
J 0
(425 -650);
DISPLAY 1.021277 (425 -650);
DISPLAY INVISIBLE (425 -650);
FORCEADD Q_RES..1
(1025 -1250);
FORCEPROP 1 LAST PART_NUMBER CS03322FB03
J 0
(975 -1150);
DISPLAY 0.787234 (975 -1150);
DISPLAY INVISIBLE (975 -1150);
FORCEPROP 1 LAST TOLERANCE 1%
J 0
(1025 -1350);
DISPLAY 0.787234 (1025 -1350);
FORCEPROP 1 LAST VALUE 33.2
J 2
(1000 -1350);
DISPLAY 0.787234 (1000 -1350);
FORCEPROP 1 LAST WATTAGE 1/16W
J 2
(1000 -1400);
DISPLAY 0.787234 (1000 -1400);
FORCEPROP 1 LAST MATERIAL CHIP
J 0
(1025 -1400);
DISPLAY 0.787234 (1025 -1400);
FORCEPROP 1 LAST PACK_TYPE 0402LF
J 0
(1275 -1400);
DISPLAY 0.787234 (1275 -1400);
FORCEPROP 1 LAST $LOCATION R4413
J 0
(800 -1250);
DISPLAY 0.638298 (800 -1250);
FORCEPROP 1 LASTPIN (925 -1250) $PN 1
J 0
(937 -1238);
DISPLAY 0.787234 (937 -1238);
PAINT MONO (937 -1238);
FORCEPROP 1 LASTPIN (1125 -1250) $PN 2
J 0
(1087 -1238);
DISPLAY 0.787234 (1087 -1238);
PAINT MONO (1087 -1238);
FORCEPROP 2 LAST CDS_LIB pure_quanta
J 0
(1025 -1250);
DISPLAY INVISIBLE (1025 -1250);
FORCEPROP 1 LAST PATH I33
J 0
(975 -1100);
DISPLAY 0.978723 (975 -1100);
PAINT WHITE (975 -1100);
DISPLAY INVISIBLE (975 -1100);
FORCEPROP 0 LAST CDS_LOCATION R4413
J 0
(975 -1100);
DISPLAY 1.021277 (975 -1100);
DISPLAY INVISIBLE (975 -1100);
FORCEPROP 0 LAST $SEC 1
J 0
(975 -1100);
DISPLAY 0.680851 (975 -1100);
PAINT MONO (975 -1100);
DISPLAY INVISIBLE (975 -1100);
FORCEPROP 0 LAST CDS_SEC 1
J 0
(975 -1100);
DISPLAY 1.021277 (975 -1100);
DISPLAY INVISIBLE (975 -1100);
FORCEADD OFFPAGE..2
(1850 -2600);
FORCEPROP 2 LAST $XR0 216 
J 0
(2039 -2600);
DISPLAY 0.638298 (2039 -2600);
PAINT MONO (2039 -2600);
FORCEPROP 2 LAST CDS_LIB standard
J 0
(1850 -2600);
DISPLAY INVISIBLE (1850 -2600);
FORCEPROP 1 LAST OFFPAGE TRUE
J 0
(2175 -2725);
DISPLAY 0.872340 (2175 -2725);
PAINT GREEN (2175 -2725);
DISPLAY INVISIBLE (2175 -2725);
FORCEPROP 1 LAST COMMENT_BODY TRUE
J 0
(1805 -2695);
DISPLAY 0.872340 (1805 -2695);
PAINT GREEN (1805 -2695);
DISPLAY INVISIBLE (1805 -2695);
FORCEPROP 2 LAST PATH I34
J 0
(2050 -2550);
DISPLAY 1.021277 (2050 -2550);
DISPLAY INVISIBLE (2050 -2550);
FORCEADD OFFPAGE..2
(1850 -1250);
FORCEPROP 2 LAST $XR0 216 
J 0
(2039 -1250);
DISPLAY 0.638298 (2039 -1250);
PAINT MONO (2039 -1250);
FORCEPROP 2 LAST CDS_LIB standard
J 0
(1850 -1250);
DISPLAY INVISIBLE (1850 -1250);
FORCEPROP 1 LAST OFFPAGE TRUE
J 0
(2175 -1375);
DISPLAY 0.872340 (2175 -1375);
PAINT GREEN (2175 -1375);
DISPLAY INVISIBLE (2175 -1375);
FORCEPROP 1 LAST COMMENT_BODY TRUE
J 0
(1805 -1345);
DISPLAY 0.872340 (1805 -1345);
PAINT GREEN (1805 -1345);
DISPLAY INVISIBLE (1805 -1345);
FORCEPROP 2 LAST PATH I35
J 0
(2050 -1200);
DISPLAY 1.021277 (2050 -1200);
DISPLAY INVISIBLE (2050 -1200);
FORCEADD UNIVERSAL_POWER..1
(375 -625);
FORCEPROP 3 LASTPIN (375 -675) SIG_NAME P3V3\g
J 0
(385 -665);
DISPLAY 0.659574 (385 -665);
PAINT MONO (385 -665);
DISPLAY INVISIBLE (385 -665);
FORCEPROP 1 LAST HDL_POWER P3V3
J 1
(375 -575);
DISPLAY 0.872340 (375 -575);
PAINT GREEN (375 -575);
FORCEPROP 2 LAST CDS_LIB logical_power
J 0
(375 -625);
PAINT MONO (375 -625);
DISPLAY INVISIBLE (375 -625);
FORCEPROP 1 LAST PATH I36
J 0
(425 -600);
DISPLAY 0.872340 (425 -600);
PAINT AQUA (425 -600);
DISPLAY INVISIBLE (425 -600);
FORCEADD Q_RES..1
(-1875 -4925);
FORCEPROP 1 LAST PART_NUMBER CS00002JB13
J 0
(-1975 -4850);
DISPLAY 0.510638 (-1975 -4850);
DISPLAY INVISIBLE (-1975 -4850);
FORCEPROP 1 LAST TOLERANCE 5%
J 0
(-1700 -4925);
DISPLAY 0.638298 (-1700 -4925);
FORCEPROP 1 LAST VALUE 0
J 2
(-1725 -4925);
DISPLAY 0.638298 (-1725 -4925);
FORCEPROP 1 LAST WATTAGE 1/16W
J 2
(-1750 -4800);
DISPLAY 0.510638 (-1750 -4800);
FORCEPROP 1 LAST MATERIAL CHIP
J 0
(-1975 -4800);
DISPLAY 0.510638 (-1975 -4800);
FORCEPROP 1 LAST PACK_TYPE 0402LF
J 0
(-1625 -4925);
DISPLAY 0.638298 (-1625 -4925);
FORCEPROP 1 LAST $LOCATION R188
J 0
(-2075 -4925);
DISPLAY 0.638298 (-2075 -4925);
FORCEPROP 1 LASTPIN (-1975 -4925) $PN 1
J 0
(-1963 -4913);
DISPLAY 0.787234 (-1963 -4913);
FORCEPROP 1 LASTPIN (-1775 -4925) $PN 2
J 0
(-1813 -4913);
DISPLAY 0.787234 (-1813 -4913);
FORCEPROP 2 LAST CDS_LIB pure_quanta
J 0
(-1875 -4925);
PAINT MONO (-1875 -4925);
DISPLAY INVISIBLE (-1875 -4925);
FORCEPROP 1 LAST PATH I4
J 0
(-1925 -4775);
DISPLAY 0.978723 (-1925 -4775);
PAINT WHITE (-1925 -4775);
DISPLAY INVISIBLE (-1925 -4775);
FORCEPROP 2 LAST CDS_LOCATION R188
J 0
(-1925 -4725);
DISPLAY 1.021277 (-1925 -4725);
DISPLAY INVISIBLE (-1925 -4725);
FORCEPROP 2 LAST $SEC 1
J 0
(-1925 -4725);
DISPLAY 0.680851 (-1925 -4725);
PAINT MONO (-1925 -4725);
DISPLAY INVISIBLE (-1925 -4725);
FORCEPROP 2 LAST CDS_SEC 1
J 0
(-1925 -4725);
DISPLAY 1.021277 (-1925 -4725);
DISPLAY INVISIBLE (-1925 -4725);
FORCEADD Q_RES..1
(-25 -5600);
FORCEPROP 1 LAST PART_NUMBER CS04992FB07
J 0
(-125 -5550);
DISPLAY 0.510638 (-125 -5550);
DISPLAY INVISIBLE (-125 -5550);
FORCEPROP 1 LAST MATERIAL CHIP
J 0
(325 -5600);
DISPLAY 0.638298 (325 -5600);
FORCEPROP 1 LAST TOLERANCE 1%
J 0
(250 -5600);
DISPLAY 0.638298 (250 -5600);
FORCEPROP 1 LAST WATTAGE 1/16W
J 2
(175 -5500);
DISPLAY 0.510638 (175 -5500);
FORCEPROP 1 LAST VALUE 49.9
J 2
(225 -5600);
DISPLAY 0.638298 (225 -5600);
FORCEPROP 1 LAST PACK_TYPE 0402LF
J 0
(-125 -5500);
DISPLAY 0.510638 (-125 -5500);
FORCEPROP 1 LAST $LOCATION R196
J 0
(-275 -5600);
DISPLAY 0.787234 (-275 -5600);
FORCEPROP 1 LASTPIN (-125 -5600) $PN 1
J 0
(-113 -5588);
DISPLAY 0.787234 (-113 -5588);
FORCEPROP 1 LASTPIN (75 -5600) $PN 2
J 0
(37 -5588);
DISPLAY 0.787234 (37 -5588);
FORCEPROP 2 LAST CDS_LIB pure_quanta
J 0
(-25 -5600);
PAINT MONO (-25 -5600);
DISPLAY INVISIBLE (-25 -5600);
FORCEPROP 1 LAST PATH I5
J 0
(-75 -5450);
DISPLAY 0.978723 (-75 -5450);
PAINT WHITE (-75 -5450);
DISPLAY INVISIBLE (-75 -5450);
FORCEPROP 2 LAST CDS_LOCATION R196
J 0
(-75 -5400);
DISPLAY 1.021277 (-75 -5400);
DISPLAY INVISIBLE (-75 -5400);
FORCEPROP 2 LAST $SEC 1
J 0
(-75 -5400);
DISPLAY 0.680851 (-75 -5400);
PAINT MONO (-75 -5400);
DISPLAY INVISIBLE (-75 -5400);
FORCEPROP 2 LAST CDS_SEC 1
J 0
(-75 -5400);
DISPLAY 1.021277 (-75 -5400);
DISPLAY INVISIBLE (-75 -5400);
FORCEADD Q_RES..1
(-25 -4925);
FORCEPROP 1 LAST PART_NUMBER CS04992FB07
J 0
(-125 -4875);
DISPLAY 0.510638 (-125 -4875);
DISPLAY INVISIBLE (-125 -4875);
FORCEPROP 1 LAST TOLERANCE 1%
J 0
(250 -4925);
DISPLAY 0.638298 (250 -4925);
FORCEPROP 1 LAST VALUE 49.9
J 2
(225 -4925);
DISPLAY 0.638298 (225 -4925);
FORCEPROP 1 LAST WATTAGE 1/16W
J 2
(175 -4825);
DISPLAY 0.510638 (175 -4825);
FORCEPROP 1 LAST PACK_TYPE 0402LF
J 0
(-125 -4825);
DISPLAY 0.510638 (-125 -4825);
FORCEPROP 1 LAST MATERIAL CHIP
J 0
(325 -4925);
DISPLAY 0.638298 (325 -4925);
FORCEPROP 1 LAST $LOCATION R195
J 0
(-275 -4925);
DISPLAY 0.787234 (-275 -4925);
FORCEPROP 1 LASTPIN (-125 -4925) $PN 1
J 0
(-113 -4913);
DISPLAY 0.787234 (-113 -4913);
FORCEPROP 1 LASTPIN (75 -4925) $PN 2
J 0
(37 -4913);
DISPLAY 0.787234 (37 -4913);
FORCEPROP 2 LAST CDS_LIB pure_quanta
J 0
(-25 -4925);
PAINT MONO (-25 -4925);
DISPLAY INVISIBLE (-25 -4925);
FORCEPROP 1 LAST PATH I6
J 0
(-75 -4775);
DISPLAY 0.978723 (-75 -4775);
PAINT WHITE (-75 -4775);
DISPLAY INVISIBLE (-75 -4775);
FORCEPROP 2 LAST CDS_LOCATION R195
J 0
(-75 -4725);
DISPLAY 1.021277 (-75 -4725);
DISPLAY INVISIBLE (-75 -4725);
FORCEPROP 2 LAST $SEC 1
J 0
(-75 -4725);
DISPLAY 0.680851 (-75 -4725);
PAINT MONO (-75 -4725);
DISPLAY INVISIBLE (-75 -4725);
FORCEPROP 2 LAST CDS_SEC 1
J 0
(-75 -4725);
DISPLAY 1.021277 (-75 -4725);
DISPLAY INVISIBLE (-75 -4725);
FORCEADD Q_RES..2
(-3375 -1850);
FORCEPROP 1 LAST PART_NUMBER CS11002FB07
J 0
(-3350 -2025);
DISPLAY 0.510638 (-3350 -2025);
DISPLAY INVISIBLE (-3350 -2025);
FORCEPROP 1 LAST PACK_TYPE 0402LF
J 0
(-3350 -2075);
DISPLAY 0.510638 (-3350 -2075);
FORCEPROP 1 LAST VALUE 100
J 0
(-3345 -1825);
DISPLAY 0.510638 (-3345 -1825);
FORCEPROP 1 LAST MATERIAL CHIP
J 0
(-3350 -1975);
DISPLAY 0.510638 (-3350 -1975);
FORCEPROP 1 LAST TOLERANCE 1%
J 0
(-3345 -1875);
DISPLAY 0.510638 (-3345 -1875);
FORCEPROP 1 LAST WATTAGE 1/16W
J 0
(-3350 -1925);
DISPLAY 0.510638 (-3350 -1925);
FORCEPROP 1 LAST LOCATION R202
J 0
(-3345 -1775);
DISPLAY 0.787234 (-3345 -1775);
FORCEPROP 1 LASTPIN (-3375 -1750) $PN 1
J 0
(-3370 -1788);
DISPLAY 0.787234 (-3370 -1788);
PAINT MONO (-3370 -1788);
FORCEPROP 1 LASTPIN (-3375 -1950) $PN 2
J 0
(-3370 -1940);
DISPLAY 0.787234 (-3370 -1940);
PAINT MONO (-3370 -1940);
FORCEPROP 2 LAST CDS_LIB pure_quanta
J 0
(-3375 -1850);
DISPLAY INVISIBLE (-3375 -1850);
FORCEPROP 1 LAST PATH I7
J 0
(-3325 -1675);
DISPLAY 0.978723 (-3325 -1675);
PAINT WHITE (-3325 -1675);
DISPLAY INVISIBLE (-3325 -1675);
FORCEPROP 0 LAST $SEC 1
J 0
(-3325 -1725);
DISPLAY 0.680851 (-3325 -1725);
PAINT MONO (-3325 -1725);
DISPLAY INVISIBLE (-3325 -1725);
FORCEPROP 0 LAST CDS_SEC 1
J 0
(-3325 -1725);
DISPLAY 1.021277 (-3325 -1725);
DISPLAY INVISIBLE (-3325 -1725);
FORCEADD Q_RES..1
(-3025 -2125);
FORCEPROP 1 LAST PART_NUMBER CS21502FB07
J 0
(-3075 -2025);
DISPLAY 0.787234 (-3075 -2025);
DISPLAY INVISIBLE (-3075 -2025);
FORCEPROP 1 LAST WATTAGE 1/16W
J 2
(-3050 -2275);
DISPLAY 0.638298 (-3050 -2275);
FORCEPROP 1 LAST VALUE 1.5K
J 2
(-3050 -2225);
DISPLAY 0.638298 (-3050 -2225);
FORCEPROP 1 LAST TOLERANCE 1%
J 0
(-3025 -2225);
DISPLAY 0.638298 (-3025 -2225);
FORCEPROP 1 LAST PACK_TYPE 0402LF
J 0
(-2925 -2225);
DISPLAY 0.638298 (-2925 -2225);
FORCEPROP 1 LAST MATERIAL CHIP
J 0
(-3025 -2275);
DISPLAY 0.638298 (-3025 -2275);
FORCEPROP 1 LAST LOCATION R206
J 0
(-3075 -2075);
DISPLAY 0.787234 (-3075 -2075);
FORCEPROP 1 LASTPIN (-3125 -2125) $PN 1
J 0
(-3113 -2113);
DISPLAY 0.787234 (-3113 -2113);
PAINT MONO (-3113 -2113);
FORCEPROP 1 LASTPIN (-2925 -2125) $PN 2
J 0
(-2963 -2113);
DISPLAY 0.787234 (-2963 -2113);
PAINT MONO (-2963 -2113);
FORCEPROP 2 LAST CDS_LIB pure_quanta
J 0
(-3025 -2125);
DISPLAY INVISIBLE (-3025 -2125);
FORCEPROP 1 LAST PATH I8
J 0
(-3075 -1975);
DISPLAY 0.978723 (-3075 -1975);
PAINT WHITE (-3075 -1975);
DISPLAY INVISIBLE (-3075 -1975);
FORCEPROP 0 LAST $SEC 1
J 0
(-3075 -1975);
DISPLAY 0.680851 (-3075 -1975);
PAINT MONO (-3075 -1975);
DISPLAY INVISIBLE (-3075 -1975);
FORCEPROP 0 LAST CDS_SEC 1
J 0
(-3075 -1975);
DISPLAY 1.021277 (-3075 -1975);
DISPLAY INVISIBLE (-3075 -1975);
FORCEADD UNIVERSAL_POWER..1
(-3375 -1650);
FORCEPROP 3 LASTPIN (-3375 -1700) SIG_NAME PVNN_TERM_CPU1\g
J 0
(-3365 -1690);
DISPLAY 0.659574 (-3365 -1690);
PAINT MONO (-3365 -1690);
DISPLAY INVISIBLE (-3365 -1690);
FORCEPROP 1 LAST HDL_POWER PVNN_TERM_CPU1
J 1
(-3375 -1600);
DISPLAY 0.872340 (-3375 -1600);
PAINT GREEN (-3375 -1600);
FORCEPROP 2 LAST CDS_LIB logical_power
J 0
(-3375 -1650);
DISPLAY INVISIBLE (-3375 -1650);
FORCEPROP 1 LAST PATH I9
J 0
(-3325 -1625);
DISPLAY 0.872340 (-3325 -1625);
PAINT AQUA (-3325 -1625);
DISPLAY INVISIBLE (-3325 -1625);
FORCEADD QUANTA_TITLE_BLOCK_C..1
(3550 -6450);
FORCEPROP 0 LAST CDS_CON_LAST_MODIFIED Fri Aug 25 14:01:43 2023
J 0
(1665 -6435);
PAINT MONO (1665 -6435);
DISPLAY INVISIBLE (1665 -6435);
FORCEPROP 2 LAST CUSTOM_TXT_CDS <XR_PAGE_TITLE>
J 0
(-4340 -1200);
DISPLAY 0.638298 (-4340 -1200);
PAINT PINK (-4340 -1200);
DISPLAY INVISIBLE (-4340 -1200);
FORCEPROP 2 LAST CUSTOM_TXT_CDS <CON_LAST_MODIFIED>
J 0
(1665 -6435);
DISPLAY 0.978723 (1665 -6435);
FORCEPROP 2 LAST CUSTOM_TXT_CDS <Q_PROJ>
J 0
(1168 -6348);
DISPLAY 1.212766 (1168 -6348);
FORCEPROP 2 LAST CUSTOM_TXT_CDS <Q_REV>
J 0
(3366 -6347);
DISPLAY 1.212766 (3366 -6347);
FORCEPROP 2 LAST CUSTOM_TXT_CDS <Q_NUMBER>
J 0
(2147 -6347);
DISPLAY 1.212766 (2147 -6347);
FORCEPROP 2 LAST CUSTOM_TXT_CDS <CON_PAGE_NUM> OF <CON_TOTAL_PAGES>
J 0
(3104 -6432);
DISPLAY 0.978723 (3104 -6432);
FORCEPROP 2 LAST CUSTOM_TXT_CDS <NAME_2>
J 0
(375 -6400);
FORCEPROP 2 LAST CUSTOM_TXT_CDS <NAME_1>
J 0
(375 -6275);
FORCEPROP 1 LAST Q_TITLE SPR CPU0 & 1- MEMTRIP/NMI
J 0
(-5716 -6449);
DISPLAY 2.446809 (-5716 -6449);
PAINT GREEN (-5716 -6449);
FORCEPROP 1 LAST Q_DEPT 
J 1
(-213 -6401);
DISPLAY 1.957447 (-213 -6401);
PAINT GREEN (-213 -6401);
FORCEPROP 2 LAST CDS_XR_PAGE_TITLE CR-123 : @S9S_MB_2U_LIB.S9S_MB_2U(SCH_1):PAGE123
J 0
(-4340 -1200);
DISPLAY 0.638298 (-4340 -1200);
PAINT PINK (-4340 -1200);
DISPLAY INVISIBLE (-4340 -1200);
FORCEPROP 2 LAST CDS_LIB pure_quanta
J 0
(3550 -6450);
PAINT MONO (3550 -6450);
DISPLAY INVISIBLE (3550 -6450);
FORCEPROP 1 LAST CDS_LMAN_SYM_OUTLINE -9475,6775,100,-125
J 0
(3550 -6450);
DISPLAY 0.468085 (3550 -6450);
PAINT GREEN (3550 -6450);
DISPLAY INVISIBLE (3550 -6450);
FORCEPROP 1 LAST COMMENT_BODY TRUE
J 0
(3562 -6463);
DISPLAY 0.978723 (3562 -6463);
PAINT GREEN (3562 -6463);
DISPLAY INVISIBLE (3562 -6463);
FORCEPROP 2 LAST PAGE_BORDER TRUE
J 0
(-4340 -1200);
DISPLAY 0.638298 (-4340 -1200);
PAINT PINK (-4340 -1200);
DISPLAY INVISIBLE (-4340 -1200);
WIRE 16 -1 (-3375 -1700)(-3375 -1750);
WIRE 16 -1 (-1975 -1925)(-1975 -2025);
WIRE 16 -1 (-3375 -350)(-3375 -400);
WIRE 16 -1 (-1975 -575)(-1975 -675);
WIRE 16 -1 (1025 -5150)(1025 -5250);
WIRE 16 -1 (1025 -4425)(1025 -4575);
WIRE 16 -1 (375 -2025)(375 -2125);
WIRE 16 -1 (375 -675)(375 -775);
WIRE 16 -1 (-375 -1975)(-375 -2000);
WIRE 16 -1 (-425 -1975)(-375 -1975);
WIRE 16 -1 (-375 -625)(-375 -650);
WIRE 16 -1 (-425 -625)(-375 -625);
WIRE 16 -1 (1800 -1250)(1125 -1250);
FORCEPROP 2 LAST SIG_NAME H_CPU0_MEMTRIP_LVC1_N
J 0
(1165 -1240);
DISPLAY 0.553191 (1165 -1240);
PAINT WHITE (1165 -1240);
WIRE 16 -1 (1800 -2600)(1125 -2600);
FORCEPROP 2 LAST SIG_NAME H_CPU1_MEMTRIP_LVC1_N
J 0
(1165 -2590);
DISPLAY 0.553191 (1165 -2590);
PAINT WHITE (1165 -2590);
WIRE 16 2175 (950 -4475)(1350 -4475);
WIRE 16 2175 (1350 -4475)(1350 -4850);
WIRE 16 2175 (950 -4475)(950 -4850);
WIRE 16 2175 (950 -4850)(1350 -4850);
WIRE 16 2175 (950 -5550)(1350 -5550);
WIRE 16 2175 (1350 -5175)(1350 -5550);
WIRE 16 2175 (950 -5175)(950 -5550);
WIRE 16 2175 (950 -5175)(1350 -5175);
WIRE 16 -1 (1025 -4925)(1150 -4925);
WIRE 16 -1 (1025 -4775)(1025 -4925);
WIRE 16 -1 (75 -4925)(1025 -4925);
FORCEPROP 2 LAST SIG_NAME H_CPU0_NMI_LVC1_N
J 0
(525 -4915);
DISPLAY 0.553191 (525 -4915);
PAINT WHITE (525 -4915);
WIRE 16 -1 (1025 -5600)(1150 -5600);
WIRE 16 -1 (1025 -5450)(1025 -5600);
WIRE 16 -1 (75 -5600)(1025 -5600);
FORCEPROP 2 LAST SIG_NAME H_CPU1_NMI_LVC1_N
J 0
(525 -5590);
DISPLAY 0.553191 (525 -5590);
PAINT WHITE (525 -5590);
WIRE 16 2175 (-4875 -2875)(2825 -2875);
WIRE 16 2175 (2825 -150)(2825 -2875);
WIRE 16 2175 (-4875 -150)(-4875 -2875);
WIRE 16 2175 (-4875 -150)(2825 -150);
WIRE 16 -1 (925 -1250)(375 -1250);
WIRE 16 -1 (375 -975)(375 -1250);
WIRE 16 -1 (-425 -1250)(-425 -1125);
WIRE 16 -1 (-425 -1250)(375 -1250);
FORCEPROP 2 LAST SIG_NAME H_CPU0_MEMTRIP_VT_N
J 0
(-250 -1240);
DISPLAY 0.553191 (-250 -1240);
PAINT WHITE (-250 -1240);
WIRE 16 -1 (375 -2325)(375 -2600);
WIRE 16 -1 (925 -2600)(375 -2600);
WIRE 16 -1 (-425 -2600)(-425 -2475);
WIRE 16 -1 (-425 -2600)(375 -2600);
FORCEPROP 2 LAST SIG_NAME H_CPU1_MEMTRIP_VT_N
J 0
(-250 -2590);
DISPLAY 0.553191 (-250 -2590);
PAINT WHITE (-250 -2590);
WIRE 16 -1 (-425 -925)(-425 -625);
WIRE 16 -1 (-425 -2275)(-425 -1975);
WIRE 16 -1 (-1150 -2375)(-575 -2375);
FORCEPROP 2 LAST SIG_NAME H_CPU1_MEMTRIP_R
J 0
(-1110 -2365);
DISPLAY 0.510638 (-1110 -2365);
PAINT WHITE (-1110 -2365);
WIRE 16 -1 (-1150 -1025)(-575 -1025);
FORCEPROP 2 LAST SIG_NAME H_CPU0_MEMTRIP_R
J 0
(-1110 -1015);
DISPLAY 0.510638 (-1110 -1015);
PAINT WHITE (-1110 -1015);
WIRE 16 -1 (-1975 -1025)(-1350 -1025);
WIRE 16 -1 (-1975 -875)(-1975 -1025);
FORCEPROP 2 LAST SIG_NAME H_CPU0_MEMTRIP
J 0
(-1935 -1015);
DISPLAY 0.510638 (-1935 -1015);
PAINT WHITE (-1935 -1015);
WIRE 16 -1 (-1975 -2375)(-1350 -2375);
WIRE 16 -1 (-1975 -2225)(-1975 -2375);
FORCEPROP 2 LAST SIG_NAME H_CPU1_MEMTRIP
J 0
(-1960 -2365);
DISPLAY 0.510638 (-1960 -2365);
PAINT WHITE (-1960 -2365);
WIRE 16 -1 (-2925 -775)(-2125 -775);
FORCEPROP 2 LAST SIG_NAME H_CPU0_MEMTRIP_OUT_VT_R_N
J 0
(-2885 -765);
DISPLAY 0.638298 (-2885 -765);
PAINT WHITE (-2885 -765);
WIRE 16 -1 (-2925 -2125)(-2125 -2125);
FORCEPROP 2 LAST SIG_NAME H_CPU1_MEMTRIP_OUT_VT_R_N
J 0
(-2885 -2115);
DISPLAY 0.638298 (-2885 -2115);
PAINT WHITE (-2885 -2115);
WIRE 16 -1 (-375 -5600)(-125 -5600);
WIRE 16 -1 (-1775 -4925)(-375 -4925);
FORCEPROP 2 LAST SIG_NAME H_CPU_NMI_LVC1_N
J 0
(-1060 -4915);
DISPLAY 0.553191 (-1060 -4915);
PAINT WHITE (-1060 -4915);
WIRE 16 -1 (-375 -4925)(-375 -5600);
WIRE 16 -1 (-125 -4925)(-375 -4925);
WIRE 16 -1 (-3525 -4925)(-1975 -4925);
FORCEPROP 2 LAST SIG_NAME H_CPU_NMI_LVC1_R_N
J 0
(-3310 -4915);
DISPLAY 0.553191 (-3310 -4915);
PAINT WHITE (-3310 -4915);
WIRE 16 -1 (-3375 -2125)(-4400 -2125);
FORCEPROP 2 LAST SIG_NAME H_CPU1_MEMTRIP_LVC1_R_N
J 0
(-4335 -2115);
DISPLAY 0.553191 (-4335 -2115);
PAINT WHITE (-4335 -2115);
WIRE 16 -1 (-3125 -2125)(-3375 -2125);
WIRE 16 -1 (-3375 -1950)(-3375 -2125);
WIRE 16 -1 (-3375 -775)(-4400 -775);
FORCEPROP 2 LAST SIG_NAME H_CPU0_MEMTRIP_LVC1_R_N
J 0
(-4335 -765);
DISPLAY 0.553191 (-4335 -765);
PAINT WHITE (-4335 -765);
WIRE 16 -1 (-3375 -600)(-3375 -775);
WIRE 16 -1 (-3125 -775)(-3375 -775);
DOT 1 (-375 -4925);
DOT 1 (-3375 -2125);
DOT 1 (-3375 -775);
DOT 1 (1025 -5600);
DOT 1 (1025 -4925);
DOT 1 (375 -2600);
DOT 1 (375 -1250);
FORCENOTE
CPU1
(-4600 -2025) 0;
DISPLAY LEFT (-4600 -2025);
DISPLAY 1.276596 (-4600 -2025);
PAINT SKYBLUE (-4600 -2025);
FORCENOTE
CPLD
(-3725 -4825) 0;
DISPLAY LEFT (-3725 -4825);
DISPLAY 1.276596 (-3725 -4825);
PAINT SKYBLUE (-3725 -4825);
FORCENOTE
CPU0
(-4575 -725) 0;
DISPLAY LEFT (-4575 -725);
DISPLAY 1.276596 (-4575 -725);
PAINT SKYBLUE (-4575 -725);
FORCENOTE
20211206 MODIFY FOR GT
(-5650 -25) 0;
DISPLAY LEFT (-5650 -25);
DISPLAY 2.510638 (-5650 -25);
PAINT PINK (-5650 -25);
FORCENOTE
20221208 CHANGE Q140,Q141 TO BA008470026
(-2325 -1550) 0;
DISPLAY LEFT (-2325 -1550);
DISPLAY 1.276596 (-2325 -1550);
PAINT PINK (-2325 -1550);
FORCENOTE
20220725 CHANGE R197,R198 TO 301 OHM
(-125 -4225) 0;
DISPLAY LEFT (-125 -4225);
DISPLAY 1.595745 (-125 -4225);
PAINT PINK (-125 -4225);
FORCENOTE
CPU1
(475 -5375) 0;
DISPLAY LEFT (475 -5375);
DISPLAY 1.276596 (475 -5375);
PAINT SKYBLUE (475 -5375);
FORCENOTE
CPU0
(450 -4650) 0;
DISPLAY LEFT (450 -4650);
DISPLAY 1.276596 (450 -4650);
PAINT SKYBLUE (450 -4650);
FORCENOTE
CPLD
(2250 -1275) 0;
DISPLAY LEFT (2250 -1275);
DISPLAY 1.276596 (2250 -1275);
PAINT SKYBLUE (2250 -1275);
FORCENOTE
CPLD
(2275 -2625) 0;
DISPLAY LEFT (2275 -2625);
DISPLAY 1.276596 (2275 -2625);
PAINT SKYBLUE (2275 -2625);
QUIT
